(kicad_pcb
	(version 20260206)
	(generator "pcbnew")
	(generator_version "10.0")
	(general
		(thickness 1.6)
		(legacy_teardrops no)
	)
	(paper "A4")
	(title_block
		(title "Bryce Canyon_R.DPB_16317-1_OCP.brd")
		(comment 1 "Bryce Canyon / footprint 1305 of 2099 (PCIE1), pads 74-76 of 76")
	)
	(layers
		(0 "F.Cu" signal "TOP")
		(4 "In1.Cu" signal "L2GND")
		(6 "In2.Cu" signal "L3")
		(8 "In3.Cu" signal "L4VCC")
		(10 "In4.Cu" signal "L5VCC")
		(12 "In5.Cu" signal "L6")
		(14 "In6.Cu" signal "L7GND")
		(2 "B.Cu" signal "BOTTOM")
		(9 "F.Adhes" user "F.Adhesive")
		(11 "B.Adhes" user "B.Adhesive")
		(13 "F.Paste" user "Package Geometry/Pastemask Top")
		(15 "B.Paste" user "Package Geometry/Pastemask Bottom")
		(5 "F.SilkS" user "Ref Des/Silkscreen Top")
		(7 "B.SilkS" user "Ref Des/Silkscreen Bottom")
		(1 "F.Mask" user "Board Geometry/Soldermask Top")
		(3 "B.Mask" user "Board Geometry/Soldermask Bottom")
		(17 "Dwgs.User" user "User.Drawings")
		(19 "Cmts.User" user "User.Comments")
		(21 "Eco1.User" user "User.Eco1")
		(23 "Eco2.User" user "User.Eco2")
		(25 "Edge.Cuts" user "Board Geometry/Outline")
		(27 "Margin" user)
		(31 "F.CrtYd" user "Package Geometry/Place Bound Top")
		(29 "B.CrtYd" user "Package Geometry/Place Bound Bottom")
		(35 "F.Fab" user "Ref Des/Assembly Top")
		(33 "B.Fab" user "Ref Des/Assembly Bottom")
	)
	(footprint ""
		(layer "F.Cu")
		(at 287.83661 -144.694402 -90)
		(property "Reference" "PCIE1"
			(at 0 0 270)
			(layer "F.SilkS")
			(hide yes)
			(effects
				(font
					(size 1.27 1.27)
				)
			)
		)
		(property "Value" "AMP-CONN76-8R-5-GP"
			(at -8.9408 -15.1892 270)
			(unlocked yes)
			(layer "F.Fab")
			(hide yes)
			(effects
				(font
					(size 1.016 1.016)
					(thickness 0.1524)
				)
			)
		)
		(property "Device Type" "PREFIT-76P-165151H483"
			(at -8.9408 -16.7132 270)
			(unlocked yes)
			(layer "F.Fab")
			(hide yes)
			(effects
				(font
					(size 1.016 1.016)
					(thickness 0.1524)
				)
			)
		)
		(duplicate_pad_numbers_are_jumpers no)
		(pad "GND26" thru_hole circle
			(at 12.599924 3.50012 270)
			(size 0.762 0.762)
			(drill 0.359918)
			(layers "*.Cu" "*.Mask")
			(remove_unused_layers no)
			(net "GND")
			(clearance 0.1651)
			(thermal_gap 0.1651)
		)
		(pad "GND27" thru_hole circle
			(at 12.599924 7.100062 270)
			(size 0.762 0.762)
			(drill 0.359918)
			(layers "*.Cu" "*.Mask")
			(remove_unused_layers no)
			(net "GND")
			(clearance 0.1651)
			(thermal_gap 0.1651)
		)
		(pad "GND28" thru_hole circle
			(at 12.599924 10.700004 270)
			(size 0.762 0.762)
			(drill 0.359918)
			(layers "*.Cu" "*.Mask")
			(remove_unused_layers no)
			(net "GND")
			(clearance 0.1651)
			(thermal_gap 0.1651)
		)
	)
)
